#ISCELL
  cls sheet_a1 *
  *
#CELL
  passive resistor *
  page9_i11
#CELL
  passive resistor *
  page9_i12
#ISCELL
  cls gnd_sg *
  page9_i14
#CELL
  clock xtal_2 *
  page9_i16
#CELL
  passive capacitor *
  page9_i17
#ISCELL
  cls vcc *
  page9_i18
#ISCELL
  cls gnd_sg *
  page9_i19
#ISCELL
  cls vcc *
  page9_i20
#CELL
  passive capacitor *
  page9_i21
#CELL
  passive ferritebead *
  page9_i22
#CELL
  passive capacitor *
  page9_i23
#CELL
  passive capacitor *
  page9_i24
#CELL
  lsi bno080_lga_28 *
  page9_i29
#CELL
  passive resistor *
  page9_i31
#CELL
  passive resistor *
  page9_i32
#ISCELL
  cls offpage_out *
  page9_i34
#ISCELL
  cls offpage_in *
  page9_i35
#CELL
  passive resistor *
  page9_i37
#CELL
  passive resistor *
  page9_i38
#ISCELL
  cls offpage_in *
  page9_i4
#CELL
  passive resistor *
  page9_i41
#ISCELL
  cls offpage_in *
  page9_i42
#CELL
  passive resistor *
  page9_i43
#CELL
  passive resistor *
  page9_i44
#ISCELL
  cls gnd_sg *
  page9_i45
#ISCELL
  cls vcc *
  page9_i46
#CELL
  passive resistor *
  page9_i47
#ISCELL
  cls gnd_sg *
  page9_i48
#CELL
  passive resistor *
  page9_i49
#ISCELL
  cls offpage_bi *
  page9_i5
#CELL
  passive resistor *
  page9_i50
#CELL
  passive resistor *
  page9_i51
#CELL
  passive resistor *
  page9_i52
#CELL
  passive capacitor *
  page9_i53
#CELL
  passive capacitor *
  page9_i54
#CELL
  passive resistor *
  page9_i55
#ISCELL
  cls vcc *
  page9_i57
#CELL
  passive resistor *
  page9_i6
#CELL
  cls tp_piont *
  page9_i63
#CELL
  passive resistor *
  page9_i64
#CELL
  passive resistor *
  page9_i65
#CELL
  passive resistor *
  page9_i66
#CELL
  passive resistor *
  page9_i67
#CELL
  passive resistor *
  page9_i7
#CELL
  passive resistor *
  page9_i70
#CELL
  cls tp_piont *
  page9_i71
#CELL
  cls tp_piont *
  page9_i72
#ISCELL
  cls offpage_in *
  page9_i74
#ISCELL
  cls offpage_out *
  page9_i75
#ISCELL
  cls offpage_in *
  page9_i76
